(kicad_pcb
	(version 20260206)
	(generator "pcbnew")
	(generator_version "10.0")
	(general
		(thickness 1.6)
		(legacy_teardrops no)
	)
	(paper "A4")
	(title_block
		(title "Wiwynn_Tioga_Pass_MB.brd")
		(comment 1 "Tioga Pass / footprints 1297-1303 of 4770")
	)
	(layers
		(0 "F.Cu" signal "TOP")
		(4 "In1.Cu" signal "L2GND")
		(6 "In2.Cu" signal "L3")
		(8 "In3.Cu" signal "L4GND")
		(10 "In4.Cu" signal "L5")
		(12 "In5.Cu" signal "L6GND")
		(14 "In6.Cu" signal "L7VCC")
		(16 "In7.Cu" signal "L8VCC")
		(18 "In8.Cu" signal "L9GND")
		(20 "In9.Cu" signal "L10")
		(22 "In10.Cu" signal "L11GND")
		(24 "In11.Cu" signal "L12")
		(26 "In12.Cu" signal "L13GND")
		(2 "B.Cu" signal "BOTTOM")
		(9 "F.Adhes" user "F.Adhesive")
		(11 "B.Adhes" user "B.Adhesive")
		(13 "F.Paste" user "Package Geometry/Pastemask Top")
		(15 "B.Paste" user "Package Geometry/Pastemask Bottom")
		(5 "F.SilkS" user "Ref Des/Silkscreen Top")
		(7 "B.SilkS" user "Ref Des/Silkscreen Bottom")
		(1 "F.Mask" user "Board Geometry/Soldermask Top")
		(3 "B.Mask" user "Board Geometry/Soldermask Bottom")
		(17 "Dwgs.User" user "User.Drawings")
		(19 "Cmts.User" user "User.Comments")
		(21 "Eco1.User" user "User.Eco1")
		(23 "Eco2.User" user "User.Eco2")
		(25 "Edge.Cuts" user "Board Geometry/Outline")
		(27 "Margin" user)
		(31 "F.CrtYd" user "Package Geometry/Place Bound Top")
		(29 "B.CrtYd" user "Package Geometry/Place Bound Bottom")
		(35 "F.Fab" user "Ref Des/Assembly Top")
		(33 "B.Fab" user "Ref Des/Assembly Bottom")
	)
	(footprint ""
		(layer "F.Cu")
		(at 485.87406 -122.91314 90)
		(property "Reference" "R9B5"
			(at 0 0 90)
			(layer "F.SilkS")
			(hide yes)
			(effects
				(font
					(size 1.27 1.27)
				)
			)
		)
		(property "Value" ""
			(at 0 0 90)
			(layer "F.Fab")
			(effects
				(font
					(size 1.27 1.27)
				)
			)
		)
		(duplicate_pad_numbers_are_jumpers no)
		(fp_rect
			(start 0.2794 0.9906)
			(end -0.2794 -0.1016)
			(stroke
				(width 0)
				(type default)
			)
			(fill no)
			(layer "F.CrtYd")
		)
		(fp_line
			(start 0.2794 -0.1016)
			(end -0.2794 -0.1016)
			(stroke
				(width 0.1)
				(type default)
			)
			(layer "F.Fab")
		)
		(fp_line
			(start -0.2794 -0.1016)
			(end -0.2794 0.9906)
			(stroke
				(width 0.1)
				(type default)
			)
			(layer "F.Fab")
		)
		(fp_line
			(start 0.2794 0.9906)
			(end 0.2794 -0.1016)
			(stroke
				(width 0.1)
				(type default)
			)
			(layer "F.Fab")
		)
		(fp_line
			(start -0.2794 0.9906)
			(end 0.2794 0.9906)
			(stroke
				(width 0.1)
				(type default)
			)
			(layer "F.Fab")
		)
		(pad "1" smd rect
			(at 0 0 90)
			(size 0.508 0.508)
			(layers "F.Cu" "F.Mask" "F.Paste")
			(net "ISENSE_TMP421_1_BC")
		)
		(pad "2" smd rect
			(at 0 0.889 90)
			(size 0.508 0.508)
			(layers "F.Cu" "F.Mask" "F.Paste")
			(net "ISENSE_TMP421_1_DXN")
		)
		(zone
			(layer "F.Cu")
			(hatch none 0.5)
			(connect_pads
				(clearance 0)
			)
			(min_thickness 0.25)
			(keepout
				(tracks allowed)
				(vias not_allowed)
				(pads allowed)
				(copperpour not_allowed)
				(footprints allowed)
			)
			(placement
				(enabled no)
				(sheetname "")
			)
			(fill
				(thermal_gap 0.5)
				(thermal_bridge_width 0.5)
				(island_removal_mode 0)
			)
			(polygon
				(pts
					(xy 486.50906 -123.16714) (xy 486.12806 -123.16714) (xy 486.12806 -122.65914) (xy 486.50906 -122.65914)
				)
			)
		)
	)
	(footprint ""
		(layer "F.Cu")
		(at -1.8542 -134.3152 90)
		(property "Reference" "CT7"
			(at -2.79273 1.3716 180)
			(unlocked yes)
			(layer "F.SilkS")
			(effects
				(font
					(size 0.7874 0.5842)
					(thickness 0.1524)
				)
				(justify left)
			)
		)
		(property "Value" ""
			(at 0 0 90)
			(layer "F.Fab")
			(effects
				(font
					(size 1.27 1.27)
				)
			)
		)
		(duplicate_pad_numbers_are_jumpers no)
		(fp_poly
			(pts
				(xy 0.3048 -0.1016) (xy 0.3048 0.9906) (xy -0.3048 0.9906) (xy -0.3048 -0.1016)
			)
			(stroke
				(width 0)
				(type default)
			)
			(fill no)
			(layer "F.CrtYd")
		)
		(fp_line
			(start 0.3048 -0.1016)
			(end -0.3048 -0.1016)
			(stroke
				(width 0.1)
				(type default)
			)
			(layer "F.Fab")
		)
		(fp_line
			(start -0.3048 -0.1016)
			(end -0.3048 0.9906)
			(stroke
				(width 0.1)
				(type default)
			)
			(layer "F.Fab")
		)
		(fp_line
			(start 0.3048 0.9906)
			(end 0.3048 -0.1016)
			(stroke
				(width 0.1)
				(type default)
			)
			(layer "F.Fab")
		)
		(fp_line
			(start -0.3048 0.9906)
			(end 0.3048 0.9906)
			(stroke
				(width 0.1)
				(type default)
			)
			(layer "F.Fab")
		)
		(pad "1" smd rect
			(at 0 0 90)
			(size 0.508 0.508)
			(layers "F.Cu" "F.Mask" "F.Paste")
			(net "VR_PVDDQ_KLM_AIREF1")
		)
		(pad "2" smd rect
			(at 0 0.889 90)
			(size 0.508 0.508)
			(layers "F.Cu" "F.Mask" "F.Paste")
			(net "GND")
		)
		(zone
			(layer "F.Cu")
			(hatch none 0.5)
			(connect_pads
				(clearance 0)
			)
			(min_thickness 0.25)
			(keepout
				(tracks allowed)
				(vias not_allowed)
				(pads allowed)
				(copperpour not_allowed)
				(footprints allowed)
			)
			(placement
				(enabled no)
				(sheetname "")
			)
			(fill
				(thermal_gap 0.5)
				(thermal_bridge_width 0.5)
				(island_removal_mode 0)
			)
			(polygon
				(pts
					(xy -1.6002 -134.0612) (xy -1.6002 -134.5692) (xy -1.2192 -134.5692) (xy -1.2192 -134.0612)
				)
			)
		)
		(zone
			(layer "F.Cu")
			(hatch none 0.5)
			(connect_pads
				(clearance 0)
			)
			(min_thickness 0.25)
			(keepout
				(tracks not_allowed)
				(vias allowed)
				(pads allowed)
				(copperpour not_allowed)
				(footprints allowed)
			)
			(placement
				(enabled no)
				(sheetname "")
			)
			(fill
				(thermal_gap 0.5)
				(thermal_bridge_width 0.5)
				(island_removal_mode 0)
			)
			(polygon
				(pts
					(xy -1.2192 -134.0612) (xy -1.2192 -134.5692) (xy -1.6002 -134.5692) (xy -1.6002 -134.0612)
				)
			)
		)
	)
	(footprint ""
		(layer "F.Cu")
		(at 368.554 -94.742 90)
		(property "Reference" "R7C8"
			(at 0 0 90)
			(layer "F.SilkS")
			(hide yes)
			(effects
				(font
					(size 1.27 1.27)
				)
			)
		)
		(property "Value" ""
			(at 0 0 90)
			(layer "F.Fab")
			(effects
				(font
					(size 1.27 1.27)
				)
			)
		)
		(duplicate_pad_numbers_are_jumpers no)
		(fp_poly
			(pts
				(xy -0.2794 -0.1016) (xy 0.2794 -0.1016) (xy 0.2794 0.9906) (xy -0.2794 0.9906)
			)
			(stroke
				(width 0)
				(type default)
			)
			(fill no)
			(layer "F.CrtYd")
		)
		(fp_line
			(start 0.2794 -0.1016)
			(end -0.2794 -0.1016)
			(stroke
				(width 0.1)
				(type default)
			)
			(layer "F.Fab")
		)
		(fp_line
			(start -0.2794 -0.1016)
			(end -0.2794 0.9906)
			(stroke
				(width 0.1)
				(type default)
			)
			(layer "F.Fab")
		)
		(fp_line
			(start 0.2794 0.9906)
			(end 0.2794 -0.1016)
			(stroke
				(width 0.1)
				(type default)
			)
			(layer "F.Fab")
		)
		(fp_line
			(start -0.2794 0.9906)
			(end 0.2794 0.9906)
			(stroke
				(width 0.1)
				(type default)
			)
			(layer "F.Fab")
		)
		(pad "1" smd rect
			(at 0 0 90)
			(size 0.508 0.508)
			(layers "F.Cu" "F.Mask" "F.Paste")
			(net "P3V3_STBY")
		)
		(pad "2" smd rect
			(at 0 0.889 90)
			(size 0.508 0.508)
			(layers "F.Cu" "F.Mask" "F.Paste")
			(net "FM_WBG_PRSNT_N")
		)
		(zone
			(layer "F.Cu")
			(hatch none 0.5)
			(connect_pads
				(clearance 0)
			)
			(min_thickness 0.25)
			(keepout
				(tracks allowed)
				(vias not_allowed)
				(pads allowed)
				(copperpour not_allowed)
				(footprints allowed)
			)
			(placement
				(enabled no)
				(sheetname "")
			)
			(fill
				(thermal_gap 0.5)
				(thermal_bridge_width 0.5)
				(island_removal_mode 0)
			)
			(polygon
				(pts
					(xy 368.808 -94.488) (xy 368.808 -94.996) (xy 369.189 -94.996) (xy 369.189 -94.488)
				)
			)
		)
		(zone
			(layer "F.Cu")
			(hatch none 0.5)
			(connect_pads
				(clearance 0)
			)
			(min_thickness 0.25)
			(keepout
				(tracks not_allowed)
				(vias allowed)
				(pads allowed)
				(copperpour not_allowed)
				(footprints allowed)
			)
			(placement
				(enabled no)
				(sheetname "")
			)
			(fill
				(thermal_gap 0.5)
				(thermal_bridge_width 0.5)
				(island_removal_mode 0)
			)
			(polygon
				(pts
					(xy 369.189 -94.488) (xy 369.189 -94.996) (xy 368.808 -94.996) (xy 368.808 -94.488)
				)
			)
		)
	)
	(footprint ""
		(layer "F.Cu")
		(at 341.3252 -154.801824 180)
		(property "Reference" "L7A1"
			(at 3.378708 -4.251706 180)
			(unlocked yes)
			(layer "F.SilkS")
			(effects
				(font
					(size 0.4064 0.254)
					(thickness 0.1524)
				)
			)
		)
		(property "Value" ""
			(at 0 0 180)
			(layer "F.Fab")
			(effects
				(font
					(size 1.27 1.27)
				)
			)
		)
		(duplicate_pad_numbers_are_jumpers no)
		(fp_line
			(start 8.3693 3.199892)
			(end -1.1303 3.199892)
			(stroke
				(width 0.1524)
				(type default)
			)
			(layer "F.SilkS")
		)
		(fp_line
			(start 8.3693 1.6637)
			(end 8.3693 3.199892)
			(stroke
				(width 0.1524)
				(type default)
			)
			(layer "F.SilkS")
		)
		(fp_line
			(start 8.3693 -3.199892)
			(end 8.3693 -1.6637)
			(stroke
				(width 0.1524)
				(type default)
			)
			(layer "F.SilkS")
		)
		(fp_line
			(start -1.1303 3.199892)
			(end -1.1303 1.6637)
			(stroke
				(width 0.1524)
				(type default)
			)
			(layer "F.SilkS")
		)
		(fp_line
			(start -1.1303 -1.6637)
			(end -1.1303 -3.199892)
			(stroke
				(width 0.1524)
				(type default)
			)
			(layer "F.SilkS")
		)
		(fp_line
			(start -1.1303 -3.199892)
			(end 8.3693 -3.199892)
			(stroke
				(width 0.1524)
				(type default)
			)
			(layer "F.SilkS")
		)
		(fp_rect
			(start -1.1303 3.199892)
			(end 8.3693 -3.199892)
			(stroke
				(width 0)
				(type default)
			)
			(fill no)
			(layer "F.CrtYd")
		)
		(fp_line
			(start 8.3693 3.199892)
			(end -1.1303 3.199892)
			(stroke
				(width 0.1)
				(type default)
			)
			(layer "F.Fab")
		)
		(fp_line
			(start 8.3693 -3.199892)
			(end 8.3693 3.199892)
			(stroke
				(width 0.1)
				(type default)
			)
			(layer "F.Fab")
		)
		(fp_line
			(start -1.1303 3.199892)
			(end -1.1303 -3.199892)
			(stroke
				(width 0.1)
				(type default)
			)
			(layer "F.Fab")
		)
		(fp_line
			(start -1.1303 -3.199892)
			(end 8.3693 -3.199892)
			(stroke
				(width 0.1)
				(type default)
			)
			(layer "F.Fab")
		)
		(pad "1" smd rect
			(at 0 0 180)
			(size 3.683 2.667)
			(layers "F.Cu" "F.Mask" "F.Paste")
			(net "VR_PVDDQ_DEF_PH1_SW")
		)
		(pad "2" smd rect
			(at 7.239 0 180)
			(size 3.683 2.667)
			(layers "F.Cu" "F.Mask" "F.Paste")
			(net "PVDDQ_DEF")
		)
	)
	(footprint ""
		(layer "F.Cu")
		(at 476.4786 -41.9989 180)
		(property "Reference" "C9E8"
			(at 0 0 180)
			(layer "F.SilkS")
			(hide yes)
			(effects
				(font
					(size 1.27 1.27)
				)
			)
		)
		(property "Value" ""
			(at 0 0 180)
			(layer "F.Fab")
			(effects
				(font
					(size 1.27 1.27)
				)
			)
		)
		(duplicate_pad_numbers_are_jumpers no)
		(fp_poly
			(pts
				(xy 0.3048 -0.1016) (xy 0.3048 0.9906) (xy -0.3048 0.9906) (xy -0.3048 -0.1016)
			)
			(stroke
				(width 0)
				(type default)
			)
			(fill no)
			(layer "F.CrtYd")
		)
		(fp_line
			(start 0.3048 0.9906)
			(end 0.3048 -0.1016)
			(stroke
				(width 0.1)
				(type default)
			)
			(layer "F.Fab")
		)
		(fp_line
			(start 0.3048 -0.1016)
			(end -0.3048 -0.1016)
			(stroke
				(width 0.1)
				(type default)
			)
			(layer "F.Fab")
		)
		(fp_line
			(start -0.3048 0.9906)
			(end 0.3048 0.9906)
			(stroke
				(width 0.1)
				(type default)
			)
			(layer "F.Fab")
		)
		(fp_line
			(start -0.3048 -0.1016)
			(end -0.3048 0.9906)
			(stroke
				(width 0.1)
				(type default)
			)
			(layer "F.Fab")
		)
		(pad "1" smd rect
			(at 0 0 180)
			(size 0.508 0.508)
			(layers "F.Cu" "F.Mask" "F.Paste")
			(net "XTAL_25MHZ_OUT_R")
		)
		(pad "2" smd rect
			(at 0 0.889 180)
			(size 0.508 0.508)
			(layers "F.Cu" "F.Mask" "F.Paste")
			(net "GND")
		)
		(zone
			(layer "F.Cu")
			(hatch none 0.5)
			(connect_pads
				(clearance 0)
			)
			(min_thickness 0.25)
			(keepout
				(tracks not_allowed)
				(vias allowed)
				(pads allowed)
				(copperpour not_allowed)
				(footprints allowed)
			)
			(placement
				(enabled no)
				(sheetname "")
			)
			(fill
				(thermal_gap 0.5)
				(thermal_bridge_width 0.5)
				(island_removal_mode 0)
			)
			(polygon
				(pts
					(xy 476.7326 -42.6339) (xy 476.2246 -42.6339) (xy 476.2246 -42.2529) (xy 476.7326 -42.2529)
				)
			)
		)
		(zone
			(layer "F.Cu")
			(hatch none 0.5)
			(connect_pads
				(clearance 0)
			)
			(min_thickness 0.25)
			(keepout
				(tracks allowed)
				(vias not_allowed)
				(pads allowed)
				(copperpour not_allowed)
				(footprints allowed)
			)
			(placement
				(enabled no)
				(sheetname "")
			)
			(fill
				(thermal_gap 0.5)
				(thermal_bridge_width 0.5)
				(island_removal_mode 0)
			)
			(polygon
				(pts
					(xy 476.7326 -42.2529) (xy 476.2246 -42.2529) (xy 476.2246 -42.6339) (xy 476.7326 -42.6339)
				)
			)
		)
	)
	(footprint ""
		(layer "F.Cu")
		(at -3.180588 -119.4435)
		(property "Reference" "U1B2"
			(at 0 0 0)
			(layer "F.SilkS")
			(hide yes)
			(effects
				(font
					(size 1.27 1.27)
				)
			)
		)
		(property "Value" "*"
			(at -0.1143 -9.3091 0)
			(unlocked yes)
			(layer "F.Fab")
			(hide yes)
			(effects
				(font
					(size 1.27 1.016)
					(thickness 0.1524)
				)
			)
		)
		(property "Device Type" "TCA9517DGKR-GP_DISCRET-G8-TCA9A"
			(at -0.1143 -10.9093 0)
			(unlocked yes)
			(layer "F.Fab")
			(hide yes)
			(effects
				(font
					(size 1.27 1.016)
					(thickness 0.1524)
				)
			)
		)
		(duplicate_pad_numbers_are_jumpers no)
		(fp_line
			(start -1.9558 -1.016)
			(end -1.9558 1.016)
			(stroke
				(width 0.1524)
				(type default)
			)
			(layer "F.SilkS")
		)
		(fp_line
			(start -1.9558 -0.5461)
			(end -1.4478 -0.0381)
			(stroke
				(width 0.1524)
				(type default)
			)
			(layer "F.SilkS")
		)
		(fp_line
			(start -1.9558 1.016)
			(end 1.0795 1.016)
			(stroke
				(width 0.1524)
				(type default)
			)
			(layer "F.SilkS")
		)
		(fp_line
			(start -1.778 1.0922)
			(end -1.778 3.048)
			(stroke
				(width 0.508)
				(type default)
			)
			(layer "F.SilkS")
		)
		(fp_line
			(start -1.4478 -0.0381)
			(end -1.9558 0.4699)
			(stroke
				(width 0.1524)
				(type default)
			)
			(layer "F.SilkS")
		)
		(fp_line
			(start 1.0795 -1.016)
			(end -1.9558 -1.016)
			(stroke
				(width 0.1524)
				(type default)
			)
			(layer "F.SilkS")
		)
		(fp_line
			(start 1.0795 1.016)
			(end 1.0795 -1.016)
			(stroke
				(width 0.1524)
				(type default)
			)
			(layer "F.SilkS")
		)
		(fp_poly
			(pts
				(xy -1.1557 -1.016) (xy -1.1557 1.016) (xy 1.1557 1.016) (xy 1.1557 -1.016)
			)
			(stroke
				(width 0)
				(type default)
			)
			(fill yes)
			(layer "F.SilkS")
		)
		(fp_rect
			(start -1.4986 2.4511)
			(end 1.4986 -2.4511)
			(stroke
				(width 0)
				(type default)
			)
			(fill no)
			(layer "F.CrtYd")
		)
		(fp_poly
			(pts
				(xy -2.032 3.302) (xy -2.032 -3.302) (xy 2.032 -3.302) (xy 2.032 -2.1209) (xy 1.4986 -2.1209) (xy 1.4986 -2.4511)
				(xy -1.4986 -2.4511) (xy -1.4986 2.4511) (xy 1.4986 2.4511) (xy 1.4986 -2.1082) (xy 2.032 -2.1082)
				(xy 2.032 3.302)
			)
			(stroke
				(width 0)
				(type default)
			)
			(fill no)
			(layer "F.CrtYd")
		)
		(fp_rect
			(start -2.032 3.302)
			(end 2.032 -3.302)
			(stroke
				(width 0)
				(type default)
			)
			(fill no)
			(layer "F.Fab")
		)
		(pad "1" smd rect
			(at -0.97536 2.05486)
			(size 0.3556 1.524)
			(layers "F.Cu" "F.Mask" "F.Paste")
			(net "PVCCIO_CPU1")
		)
		(pad "2" smd rect
			(at -0.32512 2.05486)
			(size 0.3556 1.524)
			(layers "F.Cu" "F.Mask" "F.Paste")
			(net "SMB_CPU1_PE_HP_GTL_R_SCL")
		)
		(pad "3" smd rect
			(at 0.32512 2.05486)
			(size 0.3556 1.524)
			(layers "F.Cu" "F.Mask" "F.Paste")
			(net "SMB_CPU1_PE_HP_GTL_R_SDA")
		)
		(pad "4" smd rect
			(at 0.97536 2.05486)
			(size 0.3556 1.524)
			(layers "F.Cu" "F.Mask" "F.Paste")
			(net "GND")
		)
		(pad "5" smd rect
			(at 0.97536 -2.05486)
			(size 0.3556 1.524)
			(layers "F.Cu" "F.Mask" "F.Paste")
			(net "TP_SMB_PEHPCPU1_EN")
		)
		(pad "6" smd rect
			(at 0.32512 -2.05486)
			(size 0.3556 1.524)
			(layers "F.Cu" "F.Mask" "F.Paste")
			(net "SMB_PEHPCPU1_STBY_LVC3_R_SDA")
		)
		(pad "7" smd rect
			(at -0.32512 -2.05486)
			(size 0.3556 1.524)
			(layers "F.Cu" "F.Mask" "F.Paste")
			(net "SMB_PEHPCPU1_STBY_LVC3_R_SCL")
		)
		(pad "8" smd rect
			(at -0.97536 -2.05486)
			(size 0.3556 1.524)
			(layers "F.Cu" "F.Mask" "F.Paste")
			(net "P3V3_STBY")
		)
	)
	(footprint ""
		(layer "F.Cu")
		(at 337.429602 -120.038368 -90)
		(property "Reference" "C835"
			(at -0.8382 -0.67818 270)
			(unlocked yes)
			(layer "F.SilkS")
			(effects
				(font
					(size 0.4064 0.254)
					(thickness 0.1524)
				)
				(justify left)
			)
		)
		(property "Value" ""
			(at 0 0 270)
			(layer "F.Fab")
			(effects
				(font
					(size 1.27 1.27)
				)
			)
		)
		(duplicate_pad_numbers_are_jumpers no)
		(fp_poly
			(pts
				(xy 0.3048 -0.1016) (xy 0.3048 0.9906) (xy -0.3048 0.9906) (xy -0.3048 -0.1016)
			)
			(stroke
				(width 0)
				(type default)
			)
			(fill no)
			(layer "F.CrtYd")
		)
		(fp_line
			(start -0.3048 0.9906)
			(end 0.3048 0.9906)
			(stroke
				(width 0.1)
				(type default)
			)
			(layer "F.Fab")
		)
		(fp_line
			(start 0.3048 0.9906)
			(end 0.3048 -0.1016)
			(stroke
				(width 0.1)
				(type default)
			)
			(layer "F.Fab")
		)
		(fp_line
			(start -0.3048 -0.1016)
			(end -0.3048 0.9906)
			(stroke
				(width 0.1)
				(type default)
			)
			(layer "F.Fab")
		)
		(fp_line
			(start 0.3048 -0.1016)
			(end -0.3048 -0.1016)
			(stroke
				(width 0.1)
				(type default)
			)
			(layer "F.Fab")
		)
		(pad "1" smd rect
			(at 0 0 270)
			(size 0.508 0.508)
			(layers "F.Cu" "F.Mask" "F.Paste")
			(net "P3E_CPU0_PE1_PCH_TXP<10>")
		)
		(pad "2" smd rect
			(at 0 0.889 270)
			(size 0.508 0.508)
			(layers "F.Cu" "F.Mask" "F.Paste")
			(net "P3E_CPU0_PE1_PCH_CON_TXP<10>")
		)
		(zone
			(layer "F.Cu")
			(hatch none 0.5)
			(connect_pads
				(clearance 0)
			)
			(min_thickness 0.25)
			(keepout
				(tracks not_allowed)
				(vias allowed)
				(pads allowed)
				(copperpour not_allowed)
				(footprints allowed)
			)
			(placement
				(enabled no)
				(sheetname "")
			)
			(fill
				(thermal_gap 0.5)
				(thermal_bridge_width 0.5)
				(island_removal_mode 0)
			)
			(polygon
				(pts
					(xy 336.794602 -120.292368) (xy 336.794602 -119.784368) (xy 337.175602 -119.784368) (xy 337.175602 -120.292368)
				)
			)
		)
		(zone
			(layer "F.Cu")
			(hatch none 0.5)
			(connect_pads
				(clearance 0)
			)
			(min_thickness 0.25)
			(keepout
				(tracks allowed)
				(vias not_allowed)
				(pads allowed)
				(copperpour not_allowed)
				(footprints allowed)
			)
			(placement
				(enabled no)
				(sheetname "")
			)
			(fill
				(thermal_gap 0.5)
				(thermal_bridge_width 0.5)
				(island_removal_mode 0)
			)
			(polygon
				(pts
					(xy 337.175602 -120.292368) (xy 337.175602 -119.784368) (xy 336.794602 -119.784368) (xy 336.794602 -120.292368)
				)
			)
		)
	)
)
